#ISCELL
  mstr_misc dns *
  *
#ISCELL
  pure_quanta quanta_title_block_c *
  *
#ISCELL
  logical_power universal_gnd *
  page246_i1
#CELL
  pure_quanta q_res *
  page246_i10
#ISCELL
  logical_power universal_gnd *
  page246_i100
#ISCELL
  logical_power universal_power *
  page246_i101
#CELL
  pure_quanta q_res *
  page246_i102
#ISCELL
  logical_power universal_gnd *
  page246_i103
#CELL
  pure_quanta q_res *
  page246_i104
#CELL
  pure_quanta apx80929sag7 *
  page246_i105
#ISCELL
  logical_power universal_gnd *
  page246_i106
#CELL
  pure_quanta q_cap *
  page246_i107
#ISCELL
  logical_power universal_power *
  page246_i108
#CELL
  pure_quanta q_res *
  page246_i109
#CELL
  pure_quanta q_cap *
  page246_i11
#ISCELL
  logical_power universal_gnd *
  page246_i110
#ISCELL
  logical_power universal_power *
  page246_i111
#CELL
  pure_quanta q_res *
  page246_i112
#ISCELL
  logical_power universal_gnd *
  page246_i113
#ISCELL
  logical_power universal_power *
  page246_i114
#ISCELL
  logical_power universal_gnd *
  page246_i12
#ISCELL
  logical_power universal_gnd *
  page246_i13
#CELL
  pure_quanta q_res *
  page246_i14
#ISCELL
  logical_power universal_gnd *
  page246_i15
#CELL
  pure_quanta q_res *
  page246_i17
#ISCELL
  logical_power universal_power *
  page246_i18
#CELL
  pure_quanta q_cap *
  page246_i2
#ISCELL
  logical_power universal_gnd *
  page246_i20
#CELL
  pure_quanta q_res *
  page246_i22
#ISCELL
  logical_power universal_power *
  page246_i23
#CELL
  pure_quanta q_cap *
  page246_i24
#CELL
  pure_quanta q_cap *
  page246_i25
#ISCELL
  logical_power p1v0_aux *
  page246_i26
#CELL
  pure_quanta q_res *
  page246_i27
#ISCELL
  logical_power universal_gnd *
  page246_i28
#ISCELL
  logical_power universal_power *
  page246_i3
#CELL
  pure_quanta mosfet_nch_1d3s *
  page246_i30
#ISCELL
  logical_power universal_power *
  page246_i31
#CELL
  pure_quanta bat547f *
  page246_i32
#ISCELL
  logical_power universal_power *
  page246_i34
#CELL
  pure_quanta rt9818c44gv *
  page246_i4
#ISCELL
  logical_power universal_power *
  page246_i42
#ISCELL
  logical_power universal_gnd *
  page246_i43
#CELL
  pure_quanta q_cap *
  page246_i44
#CELL
  pure_quanta q_cap *
  page246_i45
#ISCELL
  logical_power universal_gnd *
  page246_i47
#CELL
  pure_quanta q_cap *
  page246_i48
#CELL
  pure_quanta q_cap *
  page246_i49
#ISCELL
  logical_power universal_gnd *
  page246_i5
#CELL
  pure_quanta q_cap *
  page246_i50
#CELL
  pure_quanta mosfet_nch_1d3s *
  page246_i51
#ISCELL
  logical_power p1v0_aux *
  page246_i53
#CELL
  pure_quanta q_cap *
  page246_i58
#ISCELL
  logical_power universal_power *
  page246_i59
#CELL
  pure_quanta q_res *
  page246_i6
#ISCELL
  logical_power universal_gnd *
  page246_i60
#CELL
  pure_quanta q_cap *
  page246_i61
#ISCELL
  standard offpage *
  page246_i63
#ISCELL
  standard offpage *
  page246_i64
#ISCELL
  logical_power universal_gnd *
  page246_i65
#CELL
  pure_quanta mosfet_nch_gds_esd_protected *
  page246_i67
#CELL
  pure_quanta q_cap *
  page246_i68
#CELL
  pure_quanta mosfet_nch_dual *
  page246_i69
#ISCELL
  standard offpage *
  page246_i7
#CELL
  pure_quanta mosfet_nch_dual *
  page246_i76
#CELL
  pure_quanta q_res *
  page246_i77
#CELL
  pure_quanta q_res *
  page246_i78
#CELL
  pure_quanta q_res *
  page246_i79
#ISCELL
  standard offpage *
  page246_i8
#CELL
  pure_quanta q_res *
  page246_i80
#ISCELL
  logical_power universal_gnd *
  page246_i87
#CELL
  pure_quanta q_res *
  page246_i89
#CELL
  pure_quanta q_res *
  page246_i9
#CELL
  pure_quanta q_res *
  page246_i91
#ISCELL
  standard offpage *
  page246_i92
#ISCELL
  logical_power universal_power *
  page246_i93
#CELL
  pure_quanta q_cap *
  page246_i94
#ISCELL
  logical_power universal_gnd *
  page246_i95
#CELL
  pure_quanta q_res *
  page246_i96
#CELL
  pure_quanta mosfet_nch_dual *
  page246_i98
#CELL
  pure_quanta mosfet_nch_dual *
  page246_i99
